(kicad_pcb
	(version 20241229)
	(generator "pcbnew")
	(generator_version "9.0")
	(general
		(thickness 1.599998)
		(legacy_teardrops no)
	)
	(paper "A4")
	(title_block
		(date "2023-02-12")
		(rev "1.1.5")
		(comment 9 "footprints 228-233 of 473")
	)
	(layers
		(0 "F.Cu" signal)
		(4 "In1.Cu" power "In1.GND")
		(6 "In2.Cu" signal)
		(8 "In3.Cu" power "In3.GND")
		(10 "In4.Cu" power "In4.VCC")
		(12 "In5.Cu" signal)
		(14 "In6.Cu" power "In6.VCC")
		(2 "B.Cu" signal)
		(9 "F.Adhes" user "F.Adhesive")
		(11 "B.Adhes" user "B.Adhesive")
		(13 "F.Paste" user)
		(15 "B.Paste" user)
		(5 "F.SilkS" user "F.Silkscreen")
		(7 "B.SilkS" user "B.Silkscreen")
		(1 "F.Mask" user)
		(3 "B.Mask" user)
		(17 "Dwgs.User" user "User.Drawings")
		(19 "Cmts.User" user "User.Comments")
		(21 "Eco1.User" user "User.Eco1")
		(23 "Eco2.User" user "User.Eco2")
		(25 "Edge.Cuts" user)
		(27 "Margin" user)
		(31 "F.CrtYd" user "F.Courtyard")
		(29 "B.CrtYd" user "B.Courtyard")
		(35 "F.Fab" user)
		(33 "B.Fab" user)
	)
	(footprint "antmicro-footprints:C_0603_1608Metric"
		(layer "F.Cu")
		(at 135.8 52.7 90)
		(descr "Capacitor SMD 0603")
		(tags "capacitor 0603")
		(property "Reference" "C197"
			(at 1 0.3 90)
			(layer "F.SilkS")
			(effects
				(font
					(size 0.7 0.7)
					(thickness 0.15)
				)
				(justify left bottom)
			)
		)
		(property "Value" "C_22u_0603"
			(at 0 1.6 90)
			(layer "F.Fab")
			(effects
				(font
					(size 0.7 0.7)
					(thickness 0.15)
				)
				(justify left bottom)
			)
		)
		(property "Description" " "
			(at 0 0 90)
			(layer "F.Fab")
			(hide yes)
			(effects
				(font
					(size 1.27 1.27)
					(thickness 0.15)
				)
			)
		)
		(property "Author" "Antmicro"
			(at 188.5 -83.1 0)
			(layer "F.Fab")
			(hide yes)
			(effects
				(font
					(size 1 1)
					(thickness 0.15)
				)
			)
		)
		(property "Dielectric" ""
			(at 188.5 -83.1 0)
			(layer "F.Fab")
			(hide yes)
			(effects
				(font
					(size 1 1)
					(thickness 0.15)
				)
			)
		)
		(property "License" "Apache-2.0"
			(at 188.5 -83.1 0)
			(layer "F.Fab")
			(hide yes)
			(effects
				(font
					(size 1 1)
					(thickness 0.15)
				)
			)
		)
		(property "MPN" "GRM188R60J226MEA0D"
			(at 188.5 -83.1 0)
			(layer "F.Fab")
			(hide yes)
			(effects
				(font
					(size 1 1)
					(thickness 0.15)
				)
			)
		)
		(property "Manufacturer" "Murata"
			(at 188.5 -83.1 0)
			(layer "F.Fab")
			(hide yes)
			(effects
				(font
					(size 1 1)
					(thickness 0.15)
				)
			)
		)
		(property "Val" "22u"
			(at 188.5 -83.1 0)
			(layer "F.Fab")
			(hide yes)
			(effects
				(font
					(size 1 1)
					(thickness 0.15)
				)
			)
		)
		(property "Voltage" ""
			(at 188.5 -83.1 0)
			(layer "F.Fab")
			(hide yes)
			(effects
				(font
					(size 1 1)
					(thickness 0.15)
				)
			)
		)
		(sheetname "Supply")
		(sheetfile "supply.kicad_sch")
		(attr exclude_from_pos_files exclude_from_bom dnp)
		(fp_line
			(start -0.3 -0.3)
			(end 0.3 -0.3)
			(stroke
				(width 0.15)
				(type solid)
			)
			(layer "F.SilkS")
		)
		(fp_line
			(start -0.3 0.3)
			(end 0.3 0.3)
			(stroke
				(width 0.15)
				(type solid)
			)
			(layer "F.SilkS")
		)
		(fp_rect
			(start -1.24 -0.7)
			(end 1.24 0.7)
			(stroke
				(width 0.05)
				(type solid)
			)
			(fill no)
			(layer "F.CrtYd")
		)
		(fp_rect
			(start -0.8 -0.4)
			(end 0.8 0.4)
			(stroke
				(width 0.15)
				(type solid)
			)
			(fill no)
			(layer "F.Fab")
		)
		(pad "1" smd roundrect
			(at -0.7 0 90)
			(size 0.6 0.8)
			(layers "F.Cu" "F.Mask" "F.Paste")
			(roundrect_rratio 0.2)
			(net 550 "VDD1V1")
			(pintype "passive")
		)
		(pad "2" smd roundrect
			(at 0.7 0 90)
			(size 0.6 0.8)
			(layers "F.Cu" "F.Mask" "F.Paste")
			(roundrect_rratio 0.2)
			(net 5 "GND")
			(pintype "passive")
		)
	)
	(footprint "antmicro-footprints:C_0402_1005Metric"
		(layer "F.Cu")
		(at 126.9 90.974 180)
		(descr "Capacitor SMD 0402")
		(tags "capacitor SMD 0402")
		(property "Reference" "C154"
			(at 1.9 -1.226 180)
			(layer "F.SilkS")
			(effects
				(font
					(size 0.7 0.7)
					(thickness 0.15)
				)
				(justify left bottom)
			)
		)
		(property "Value" "C_10u_0402"
			(at 0 1.4 180)
			(layer "F.Fab")
			(effects
				(font
					(size 0.7 0.7)
					(thickness 0.15)
				)
				(justify left bottom)
			)
		)
		(property "Description" " "
			(at 0 0 180)
			(layer "F.Fab")
			(hide yes)
			(effects
				(font
					(size 1.27 1.27)
					(thickness 0.15)
				)
			)
		)
		(property "Author" "Antmicro"
			(at 253.8 181.948 0)
			(layer "F.Fab")
			(hide yes)
			(effects
				(font
					(size 1 1)
					(thickness 0.15)
				)
			)
		)
		(property "Dielectric" ""
			(at 253.8 181.948 0)
			(layer "F.Fab")
			(hide yes)
			(effects
				(font
					(size 1 1)
					(thickness 0.15)
				)
			)
		)
		(property "License" "Apache-2.0"
			(at 253.8 181.948 0)
			(layer "F.Fab")
			(hide yes)
			(effects
				(font
					(size 1 1)
					(thickness 0.15)
				)
			)
		)
		(property "MPN" "CC0402MRX5R5BB106"
			(at 253.8 181.948 0)
			(layer "F.Fab")
			(hide yes)
			(effects
				(font
					(size 1 1)
					(thickness 0.15)
				)
			)
		)
		(property "Manufacturer" "Yaego"
			(at 253.8 181.948 0)
			(layer "F.Fab")
			(hide yes)
			(effects
				(font
					(size 1 1)
					(thickness 0.15)
				)
			)
		)
		(property "Val" "10u"
			(at 253.8 181.948 0)
			(layer "F.Fab")
			(hide yes)
			(effects
				(font
					(size 1 1)
					(thickness 0.15)
				)
			)
		)
		(property "Voltage" ""
			(at 253.8 181.948 0)
			(layer "F.Fab")
			(hide yes)
			(effects
				(font
					(size 1 1)
					(thickness 0.15)
				)
			)
		)
		(sheetname "Supply")
		(sheetfile "supply.kicad_sch")
		(attr smd)
		(fp_rect
			(start -0.94 -0.47)
			(end 0.94 0.47)
			(stroke
				(width 0.05)
				(type solid)
			)
			(fill no)
			(layer "F.CrtYd")
		)
		(fp_rect
			(start -0.499 -0.249)
			(end 0.499 0.249)
			(stroke
				(width 0.15)
				(type solid)
			)
			(fill no)
			(layer "F.Fab")
		)
		(pad "1" smd roundrect
			(at -0.484 0 180)
			(size 0.59 0.64)
			(layers "F.Cu" "F.Mask" "F.Paste")
			(roundrect_rratio 0.25)
			(net 463 "VCC5V0_INT")
			(pintype "passive")
		)
		(pad "2" smd roundrect
			(at 0.484 0 180)
			(size 0.59 0.64)
			(layers "F.Cu" "F.Mask" "F.Paste")
			(roundrect_rratio 0.25)
			(net 5 "GND")
			(pintype "passive")
		)
	)
	(footprint "antmicro-footprints:R_0402_1005Metric"
		(layer "F.Cu")
		(at 129.9825 99.549 180)
		(descr "Resistor SMD 0402")
		(tags "resistor SMD 0402")
		(property "Reference" "R124"
			(at -0.7175 -0.451 180)
			(layer "F.SilkS")
			(effects
				(font
					(size 0.7 0.7)
					(thickness 0.15)
				)
				(justify left bottom)
			)
		)
		(property "Value" "R_0R_0402"
			(at 0 1.4 180)
			(layer "F.Fab")
			(effects
				(font
					(size 0.7 0.7)
					(thickness 0.15)
				)
				(justify left bottom)
			)
		)
		(property "Description" "0R resistor in 0402 package with unspecified tolerance"
			(at 0 0 180)
			(layer "F.Fab")
			(hide yes)
			(effects
				(font
					(size 1.27 1.27)
					(thickness 0.15)
				)
			)
		)
		(property "Author" "Antmicro"
			(at 259.965 199.098 0)
			(layer "F.Fab")
			(hide yes)
			(effects
				(font
					(size 1 1)
					(thickness 0.15)
				)
			)
		)
		(property "Current" "1A"
			(at 259.965 199.098 0)
			(layer "F.Fab")
			(hide yes)
			(effects
				(font
					(size 1 1)
					(thickness 0.15)
				)
			)
		)
		(property "License" "Apache-2.0"
			(at 259.965 199.098 0)
			(layer "F.Fab")
			(hide yes)
			(effects
				(font
					(size 1 1)
					(thickness 0.15)
				)
			)
		)
		(property "MPN" "ERJ2GE0R00X"
			(at 259.965 199.098 0)
			(layer "F.Fab")
			(hide yes)
			(effects
				(font
					(size 1 1)
					(thickness 0.15)
				)
			)
		)
		(property "Manufacturer" "Panasonic"
			(at 259.965 199.098 0)
			(layer "F.Fab")
			(hide yes)
			(effects
				(font
					(size 1 1)
					(thickness 0.15)
				)
			)
		)
		(property "Tolerance" ""
			(at 259.965 199.098 0)
			(layer "F.Fab")
			(hide yes)
			(effects
				(font
					(size 1 1)
					(thickness 0.15)
				)
			)
		)
		(property "Val" "0R"
			(at 259.965 199.098 0)
			(layer "F.Fab")
			(hide yes)
			(effects
				(font
					(size 1 1)
					(thickness 0.15)
				)
			)
		)
		(sheetname "Supply")
		(sheetfile "supply.kicad_sch")
		(attr smd)
		(fp_rect
			(start -0.93 -0.47)
			(end 0.93 0.47)
			(stroke
				(width 0.05)
				(type solid)
			)
			(fill no)
			(layer "F.CrtYd")
		)
		(fp_rect
			(start -0.5 -0.25)
			(end 0.5 0.25)
			(stroke
				(width 0.15)
				(type solid)
			)
			(fill no)
			(layer "F.Fab")
		)
		(pad "1" smd roundrect
			(at -0.485 0 180)
			(size 0.59 0.64)
			(layers "F.Cu" "F.Mask" "F.Paste")
			(roundrect_rratio 0.25)
			(net 593 "/Supply/1V0_VCC_INT")
			(pintype "passive")
		)
		(pad "2" smd roundrect
			(at 0.485 0 180)
			(size 0.59 0.64)
			(layers "F.Cu" "F.Mask" "F.Paste")
			(roundrect_rratio 0.25)
			(net 611 "/Supply/1V0_FSEL")
			(pintype "passive")
		)
	)
	(footprint "antmicro-footprints:LED_0603_1608Metric_G"
		(layer "F.Cu")
		(at 137.7825 92.099)
		(descr "LED SMD 0603 Green")
		(tags "LED SMD 0603 Green")
		(property "Reference" "PWR3"
			(at -4.6825 -0.799 0)
			(layer "F.SilkS")
			(effects
				(font
					(size 0.7 0.7)
					(thickness 0.15)
				)
				(justify left bottom)
			)
		)
		(property "Value" "LED_G_0603_KP-1608CGCK"
			(at 0 1.6 0)
			(layer "F.Fab")
			(effects
				(font
					(size 0.7 0.7)
					(thickness 0.15)
				)
				(justify left bottom)
			)
		)
		(property "Author" "Antmicro"
			(at 0 0 0)
			(layer "F.Fab")
			(hide yes)
			(effects
				(font
					(size 1 1)
					(thickness 0.15)
				)
			)
		)
		(property "License" "Apache-2.0"
			(at 0 0 0)
			(layer "F.Fab")
			(hide yes)
			(effects
				(font
					(size 1 1)
					(thickness 0.15)
				)
			)
		)
		(property "MPN" "KP-1608CGCK"
			(at 0 0 0)
			(layer "F.Fab")
			(hide yes)
			(effects
				(font
					(size 1 1)
					(thickness 0.15)
				)
			)
		)
		(property "Manufacturer" "Kingbright"
			(at 0 0 0)
			(layer "F.Fab")
			(hide yes)
			(effects
				(font
					(size 1 1)
					(thickness 0.15)
				)
			)
		)
		(sheetname "Supply")
		(sheetfile "supply.kicad_sch")
		(attr smd)
		(fp_line
			(start -0.27 -0.35)
			(end 0.27 -0.35)
			(stroke
				(width 0.15)
				(type solid)
			)
			(layer "F.SilkS")
		)
		(fp_line
			(start -0.27 0.351)
			(end 0.27 0.351)
			(stroke
				(width 0.15)
				(type solid)
			)
			(layer "F.SilkS")
		)
		(fp_line
			(start -0.106328 -0.200008)
			(end -0.106328 0.199992)
			(stroke
				(width 0.1)
				(type solid)
			)
			(layer "F.SilkS")
		)
		(fp_line
			(start -0.106328 -0.200008)
			(end 0.093672 -8e-06)
			(stroke
				(width 0.1)
				(type solid)
			)
			(layer "F.SilkS")
		)
		(fp_line
			(start -0.106328 -8e-06)
			(end -0.29 0)
			(stroke
				(width 0.1)
				(type solid)
			)
			(layer "F.SilkS")
		)
		(fp_line
			(start 0.093672 -0.200008)
			(end 0.093672 0.199992)
			(stroke
				(width 0.1)
				(type solid)
			)
			(layer "F.SilkS")
		)
		(fp_line
			(start 0.093672 -8e-06)
			(end -0.106328 0.199992)
			(stroke
				(width 0.1)
				(type solid)
			)
			(layer "F.SilkS")
		)
		(fp_line
			(start 0.093672 -8e-06)
			(end 0.293672 -8e-06)
			(stroke
				(width 0.1)
				(type solid)
			)
			(layer "F.SilkS")
		)
		(fp_line
			(start 1.25 0.32)
			(end 1.25 -0.32)
			(stroke
				(width 0.15)
				(type solid)
			)
			(layer "F.SilkS")
		)
		(fp_rect
			(start 1.26 0.65)
			(end -1.26 -0.65)
			(stroke
				(width 0.05)
				(type solid)
			)
			(fill no)
			(layer "F.CrtYd")
		)
		(fp_line
			(start -0.599 0)
			(end -0.201 0)
			(stroke
				(width 0.15)
				(type solid)
			)
			(layer "F.Fab")
		)
		(fp_line
			(start -0.201 -0.2)
			(end -0.201 0)
			(stroke
				(width 0.15)
				(type solid)
			)
			(layer "F.Fab")
		)
		(fp_line
			(start -0.201 0)
			(end -0.201 0.202)
			(stroke
				(width 0.15)
				(type solid)
			)
			(layer "F.Fab")
		)
		(fp_line
			(start -0.201 0.202)
			(end 0.101 0)
			(stroke
				(width 0.15)
				(type solid)
			)
			(layer "F.Fab")
		)
		(fp_line
			(start 0.101 0)
			(end -0.201 -0.2)
			(stroke
				(width 0.15)
				(type solid)
			)
			(layer "F.Fab")
		)
		(fp_line
			(start 0.199 -0.2)
			(end 0.199 -0.1)
			(stroke
				(width 0.15)
				(type solid)
			)
			(layer "F.Fab")
		)
		(fp_line
			(start 0.199 0)
			(end 0.597 0)
			(stroke
				(width 0.15)
				(type solid)
			)
			(layer "F.Fab")
		)
		(fp_line
			(start 0.199 0.202)
			(end 0.199 -0.1)
			(stroke
				(width 0.15)
				(type solid)
			)
			(layer "F.Fab")
		)
		(fp_rect
			(start -0.848 -0.4)
			(end 0.85 0.402)
			(stroke
				(width 0.15)
				(type solid)
			)
			(fill no)
			(layer "F.Fab")
		)
		(pad "1" smd rect
			(at -0.75 0 180)
			(size 0.8 0.8)
			(layers "F.Cu" "F.Mask" "F.Paste")
			(net 459 "3V3_SYS")
			(pinfunction "1")
			(pintype "passive")
		)
		(pad "2" smd rect
			(at 0.75 0 180)
			(size 0.8 0.8)
			(layers "F.Cu" "F.Mask" "F.Paste")
			(net 555 "Net-(PWR3-Pad2)")
			(pinfunction "2")
			(pintype "passive")
		)
	)
	(footprint "antmicro-footprints:LED_0603_1608Metric_G"
		(layer "F.Cu")
		(at 137.7825 87.099)
		(descr "LED SMD 0603 Green")
		(tags "LED SMD 0603 Green")
		(property "Reference" "PWR4"
			(at -4.6825 -0.799 0)
			(layer "F.SilkS")
			(effects
				(font
					(size 0.7 0.7)
					(thickness 0.15)
				)
				(justify left bottom)
			)
		)
		(property "Value" "LED_G_0603_KP-1608CGCK"
			(at 0 1.6 0)
			(layer "F.Fab")
			(effects
				(font
					(size 0.7 0.7)
					(thickness 0.15)
				)
				(justify left bottom)
			)
		)
		(property "Author" "Antmicro"
			(at 0 0 0)
			(layer "F.Fab")
			(hide yes)
			(effects
				(font
					(size 1 1)
					(thickness 0.15)
				)
			)
		)
		(property "License" "Apache-2.0"
			(at 0 0 0)
			(layer "F.Fab")
			(hide yes)
			(effects
				(font
					(size 1 1)
					(thickness 0.15)
				)
			)
		)
		(property "MPN" "KP-1608CGCK"
			(at 0 0 0)
			(layer "F.Fab")
			(hide yes)
			(effects
				(font
					(size 1 1)
					(thickness 0.15)
				)
			)
		)
		(property "Manufacturer" "Kingbright"
			(at 0 0 0)
			(layer "F.Fab")
			(hide yes)
			(effects
				(font
					(size 1 1)
					(thickness 0.15)
				)
			)
		)
		(sheetname "Supply")
		(sheetfile "supply.kicad_sch")
		(attr smd)
		(fp_line
			(start -0.27 -0.35)
			(end 0.27 -0.35)
			(stroke
				(width 0.15)
				(type solid)
			)
			(layer "F.SilkS")
		)
		(fp_line
			(start -0.27 0.351)
			(end 0.27 0.351)
			(stroke
				(width 0.15)
				(type solid)
			)
			(layer "F.SilkS")
		)
		(fp_line
			(start -0.106328 -0.200008)
			(end -0.106328 0.199992)
			(stroke
				(width 0.1)
				(type solid)
			)
			(layer "F.SilkS")
		)
		(fp_line
			(start -0.106328 -0.200008)
			(end 0.093672 -8e-06)
			(stroke
				(width 0.1)
				(type solid)
			)
			(layer "F.SilkS")
		)
		(fp_line
			(start -0.106328 -8e-06)
			(end -0.29 0)
			(stroke
				(width 0.1)
				(type solid)
			)
			(layer "F.SilkS")
		)
		(fp_line
			(start 0.093672 -0.200008)
			(end 0.093672 0.199992)
			(stroke
				(width 0.1)
				(type solid)
			)
			(layer "F.SilkS")
		)
		(fp_line
			(start 0.093672 -8e-06)
			(end -0.106328 0.199992)
			(stroke
				(width 0.1)
				(type solid)
			)
			(layer "F.SilkS")
		)
		(fp_line
			(start 0.093672 -8e-06)
			(end 0.293672 -8e-06)
			(stroke
				(width 0.1)
				(type solid)
			)
			(layer "F.SilkS")
		)
		(fp_line
			(start 1.25 0.32)
			(end 1.25 -0.32)
			(stroke
				(width 0.15)
				(type solid)
			)
			(layer "F.SilkS")
		)
		(fp_rect
			(start 1.26 0.65)
			(end -1.26 -0.65)
			(stroke
				(width 0.05)
				(type solid)
			)
			(fill no)
			(layer "F.CrtYd")
		)
		(fp_line
			(start -0.599 0)
			(end -0.201 0)
			(stroke
				(width 0.15)
				(type solid)
			)
			(layer "F.Fab")
		)
		(fp_line
			(start -0.201 -0.2)
			(end -0.201 0)
			(stroke
				(width 0.15)
				(type solid)
			)
			(layer "F.Fab")
		)
		(fp_line
			(start -0.201 0)
			(end -0.201 0.202)
			(stroke
				(width 0.15)
				(type solid)
			)
			(layer "F.Fab")
		)
		(fp_line
			(start -0.201 0.202)
			(end 0.101 0)
			(stroke
				(width 0.15)
				(type solid)
			)
			(layer "F.Fab")
		)
		(fp_line
			(start 0.101 0)
			(end -0.201 -0.2)
			(stroke
				(width 0.15)
				(type solid)
			)
			(layer "F.Fab")
		)
		(fp_line
			(start 0.199 -0.2)
			(end 0.199 -0.1)
			(stroke
				(width 0.15)
				(type solid)
			)
			(layer "F.Fab")
		)
		(fp_line
			(start 0.199 0)
			(end 0.597 0)
			(stroke
				(width 0.15)
				(type solid)
			)
			(layer "F.Fab")
		)
		(fp_line
			(start 0.199 0.202)
			(end 0.199 -0.1)
			(stroke
				(width 0.15)
				(type solid)
			)
			(layer "F.Fab")
		)
		(fp_rect
			(start -0.848 -0.4)
			(end 0.85 0.402)
			(stroke
				(width 0.15)
				(type solid)
			)
			(fill no)
			(layer "F.Fab")
		)
		(pad "1" smd rect
			(at -0.75 0 180)
			(size 0.8 0.8)
			(layers "F.Cu" "F.Mask" "F.Paste")
			(net 459 "3V3_SYS")
			(pinfunction "1")
			(pintype "passive")
		)
		(pad "2" smd rect
			(at 0.75 0 180)
			(size 0.8 0.8)
			(layers "F.Cu" "F.Mask" "F.Paste")
			(net 556 "Net-(PWR4-Pad2)")
			(pinfunction "2")
			(pintype "passive")
		)
	)
	(footprint "antmicro-footprints:R_0402_1005Metric"
		(layer "F.Cu")
		(at 111.94 100.449)
		(descr "Resistor SMD 0402")
		(tags "resistor SMD 0402")
		(property "Reference" "R129"
			(at -3.64 0.351 0)
			(layer "F.SilkS")
			(effects
				(font
					(size 0.7 0.7)
					(thickness 0.15)
				)
				(justify left bottom)
			)
		)
		(property "Value" "R_0R_0402"
			(at 0 1.4 0)
			(layer "F.Fab")
			(effects
				(font
					(size 0.7 0.7)
					(thickness 0.15)
				)
				(justify left bottom)
			)
		)
		(property "Description" "0R resistor in 0402 package with unspecified tolerance"
			(at 0 0 0)
			(layer "F.Fab")
			(hide yes)
			(effects
				(font
					(size 1.27 1.27)
					(thickness 0.15)
				)
			)
		)
		(property "Author" "Antmicro"
			(at 0 0 0)
			(layer "F.Fab")
			(hide yes)
			(effects
				(font
					(size 1 1)
					(thickness 0.15)
				)
			)
		)
		(property "Current" "1A"
			(at 0 0 0)
			(layer "F.Fab")
			(hide yes)
			(effects
				(font
					(size 1 1)
					(thickness 0.15)
				)
			)
		)
		(property "License" "Apache-2.0"
			(at 0 0 0)
			(layer "F.Fab")
			(hide yes)
			(effects
				(font
					(size 1 1)
					(thickness 0.15)
				)
			)
		)
		(property "MPN" "ERJ2GE0R00X"
			(at 0 0 0)
			(layer "F.Fab")
			(hide yes)
			(effects
				(font
					(size 1 1)
					(thickness 0.15)
				)
			)
		)
		(property "Manufacturer" "Panasonic"
			(at 0 0 0)
			(layer "F.Fab")
			(hide yes)
			(effects
				(font
					(size 1 1)
					(thickness 0.15)
				)
			)
		)
		(property "Tolerance" ""
			(at 0 0 0)
			(layer "F.Fab")
			(hide yes)
			(effects
				(font
					(size 1 1)
					(thickness 0.15)
				)
			)
		)
		(property "Val" "0R"
			(at 0 0 0)
			(layer "F.Fab")
			(hide yes)
			(effects
				(font
					(size 1 1)
					(thickness 0.15)
				)
			)
		)
		(sheetname "Supply")
		(sheetfile "supply.kicad_sch")
		(attr smd)
		(fp_rect
			(start -0.93 -0.47)
			(end 0.93 0.47)
			(stroke
				(width 0.05)
				(type solid)
			)
			(fill no)
			(layer "F.CrtYd")
		)
		(fp_rect
			(start -0.5 -0.25)
			(end 0.5 0.25)
			(stroke
				(width 0.15)
				(type solid)
			)
			(fill no)
			(layer "F.Fab")
		)
		(pad "1" smd roundrect
			(at -0.485 0)
			(size 0.59 0.64)
			(layers "F.Cu" "F.Mask" "F.Paste")
			(roundrect_rratio 0.25)
			(net 5 "GND")
			(pintype "passive")
		)
		(pad "2" smd roundrect
			(at 0.485 0)
			(size 0.59 0.64)
			(layers "F.Cu" "F.Mask" "F.Paste")
			(roundrect_rratio 0.25)
			(net 618 "/Supply/3V3_SS{slash}TR")
			(pintype "passive")
		)
	)
)
